# T6G (Grand Teton) — schematic netlist excerpt (pin names and nets, part order shuffled) for the footprints in the layout excerpt that follows; sources: Cadence DE-HDL packaged netlist, KiCad conversion of 04192023_DAF0TMB3IC0_F0TG_MB_C_brd_V02_OCP.brd

R6200  Q_RES  0 5% CHIP  pkg 0402LF  page 250 : A = SMB_USB_CPU0_HUB1_SDA_R ; B = SMB_USB_CPU0_HUB1_SDA
PC1649  Q_CAP  0.1UF 25V 10% X6S  pkg C0402  page 190 : A = P12V_AUX ; B = GND
H10  HOLE  EMPTY  pkg TH  page 230 : \1\ = GND

(kicad_pcb
	(version 20260206)
	(generator "pcbnew")
	(generator_version "10.0")
	(general
		(thickness 1.6)
		(legacy_teardrops no)
	)
	(paper "A4")
	(title_block
		(title "04192023_DAF0TMB3IC0_F0TG_MB_C_brd_V02_OCP.brd")
		(comment 1 "Grand Teton / footprints 102-104 of 8354")
	)
	(layers
		(0 "F.Cu" signal "TOP")
		(4 "In1.Cu" signal "GND")
		(6 "In2.Cu" signal "IN1")
		(8 "In3.Cu" signal "GND1")
		(10 "In4.Cu" signal "IN2")
		(12 "In5.Cu" signal "GND2")
		(14 "In6.Cu" signal "IN3")
		(16 "In7.Cu" signal "GND3")
		(18 "In8.Cu" signal "VCC")
		(20 "In9.Cu" signal "VCC1")
		(22 "In10.Cu" signal "GND4")
		(24 "In11.Cu" signal "IN4")
		(26 "In12.Cu" signal "GND5")
		(28 "In13.Cu" signal "IN5")
		(30 "In14.Cu" signal "GND6")
		(32 "In15.Cu" signal "IN6")
		(34 "In16.Cu" signal "GND7")
		(2 "B.Cu" signal "BOTTOM")
		(9 "F.Adhes" user "F.Adhesive")
		(11 "B.Adhes" user "B.Adhesive")
		(13 "F.Paste" user "Package Geometry/Pastemask Top")
		(15 "B.Paste" user "Package Geometry/Pastemask Bottom")
		(5 "F.SilkS" user "Ref Des/Silkscreen Top")
		(7 "B.SilkS" user "Ref Des/Silkscreen Bottom")
		(1 "F.Mask" user "Board Geometry/Soldermask Top")
		(3 "B.Mask" user "Board Geometry/Soldermask Bottom")
		(17 "Dwgs.User" user "User.Drawings")
		(19 "Cmts.User" user "User.Comments")
		(21 "Eco1.User" user "User.Eco1")
		(23 "Eco2.User" user "User.Eco2")
		(25 "Edge.Cuts" user "Board Geometry/Outline")
		(27 "Margin" user)
		(31 "F.CrtYd" user "Package Geometry/Place Bound Top")
		(29 "B.CrtYd" user "Package Geometry/Place Bound Bottom")
		(35 "F.Fab" user "Ref Des/Assembly Top")
		(33 "B.Fab" user "Ref Des/Assembly Bottom")
	)
	(footprint ""
		(layer "F.Cu")
		(at 439.512456 -43.929554 90)
		(property "Reference" "PC1649"
			(at 0 0 90)
			(layer "F.SilkS")
			(hide yes)
			(effects
				(font
					(size 1.27 1.27)
				)
			)
		)
		(property "Value" ""
			(at 0 0 90)
			(layer "F.Fab")
			(effects
				(font
					(size 1.27 1.27)
				)
			)
		)
		(duplicate_pad_numbers_are_jumpers no)
		(fp_line
			(start 0.7874 -0.4064)
			(end 0.7874 0.4064)
			(stroke
				(width 0.1524)
				(type default)
			)
			(layer "F.SilkS")
		)
		(fp_line
			(start -0.7874 -0.4064)
			(end 0.7874 -0.4064)
			(stroke
				(width 0.1524)
				(type default)
			)
			(layer "F.SilkS")
		)
		(fp_line
			(start 0.7874 0.4064)
			(end -0.7874 0.4064)
			(stroke
				(width 0.1524)
				(type default)
			)
			(layer "F.SilkS")
		)
		(fp_line
			(start -0.7874 0.4064)
			(end -0.7874 -0.4064)
			(stroke
				(width 0.1524)
				(type default)
			)
			(layer "F.SilkS")
		)
		(fp_line
			(start -0.12065 -0.305054)
			(end -0.12065 -0.2794)
			(stroke
				(width 0.1)
				(type default)
			)
			(layer "F.Fab")
		)
		(fp_line
			(start -0.67945 -0.305054)
			(end -0.12065 -0.305054)
			(stroke
				(width 0.1)
				(type default)
			)
			(layer "F.Fab")
		)
		(fp_line
			(start 0.67945 -0.3048)
			(end 0.67945 0.3048)
			(stroke
				(width 0.1)
				(type default)
			)
			(layer "F.Fab")
		)
		(fp_line
			(start 0.12065 -0.3048)
			(end 0.67945 -0.3048)
			(stroke
				(width 0.1)
				(type default)
			)
			(layer "F.Fab")
		)
		(fp_line
			(start 0.12065 -0.2794)
			(end 0.12065 -0.3048)
			(stroke
				(width 0.1)
				(type default)
			)
			(layer "F.Fab")
		)
		(fp_line
			(start -0.12065 -0.2794)
			(end 0.12065 -0.2794)
			(stroke
				(width 0.1)
				(type default)
			)
			(layer "F.Fab")
		)
		(fp_line
			(start 0.120396 0.2794)
			(end -0.12065 0.2794)
			(stroke
				(width 0.1)
				(type default)
			)
			(layer "F.Fab")
		)
		(fp_line
			(start -0.12065 0.2794)
			(end -0.12065 0.3048)
			(stroke
				(width 0.1)
				(type default)
			)
			(layer "F.Fab")
		)
		(fp_line
			(start 0.67945 0.3048)
			(end 0.120396 0.3048)
			(stroke
				(width 0.1)
				(type default)
			)
			(layer "F.Fab")
		)
		(fp_line
			(start 0.120396 0.3048)
			(end 0.120396 0.2794)
			(stroke
				(width 0.1)
				(type default)
			)
			(layer "F.Fab")
		)
		(fp_line
			(start -0.12065 0.3048)
			(end -0.67945 0.3048)
			(stroke
				(width 0.1)
				(type default)
			)
			(layer "F.Fab")
		)
		(fp_line
			(start -0.67945 0.3048)
			(end -0.67945 -0.305054)
			(stroke
				(width 0.1)
				(type default)
			)
			(layer "F.Fab")
		)
		(pad "1" smd circle
			(at -0.40005 0 90)
			(size 0 0)
			(layers "F.Cu" "F.Mask" "F.Paste")
			(net "P12V_AUX")
		)
		(pad "2" smd circle
			(at 0.40005 0 90)
			(size 0 0)
			(layers "F.Cu" "F.Mask" "F.Paste")
			(net "GND")
		)
	)
	(footprint ""
		(layer "F.Cu")
		(at 435.43982 -399.029936)
		(property "Reference" "H10"
			(at -3.815588 -3.882644 0)
			(unlocked yes)
			(layer "F.SilkS")
			(effects
				(font
					(size 0.7874 0.5842)
					(thickness 0.1524)
				)
				(justify left)
			)
		)
		(property "Value" ""
			(at 0 0 0)
			(layer "F.Fab")
			(effects
				(font
					(size 1.27 1.27)
				)
			)
		)
		(duplicate_pad_numbers_are_jumpers no)
		(pad "1" thru_hole circle
			(at 0 0)
			(size 6.1976 6.1976)
			(drill 3.7338)
			(layers "*.Cu" "*.Mask")
			(remove_unused_layers no)
			(net "GND")
			(clearance -0.9779)
			(padstack
				(mode front_inner_back)
				(layer "Inner"
					(shape circle)
					(size 5.5372 5.5372)
					(clearance -0.6477)
				)
				(layer "B.Cu"
					(shape circle)
					(size 6.1976 6.1976)
					(clearance -0.9779)
				)
			)
		)
	)
	(footprint ""
		(layer "F.Cu")
		(at 279.513792 -120.74017 180)
		(property "Reference" "R6200"
			(at 0 0 180)
			(layer "F.SilkS")
			(hide yes)
			(effects
				(font
					(size 1.27 1.27)
				)
			)
		)
		(property "Value" ""
			(at 0 0 180)
			(layer "F.Fab")
			(effects
				(font
					(size 1.27 1.27)
				)
			)
		)
		(duplicate_pad_numbers_are_jumpers no)
		(fp_line
			(start 0.7874 0.4064)
			(end -0.7874 0.4064)
			(stroke
				(width 0.1524)
				(type default)
			)
			(layer "F.SilkS")
		)
		(fp_line
			(start 0.7874 -0.4064)
			(end 0.7874 0.4064)
			(stroke
				(width 0.1524)
				(type default)
			)
			(layer "F.SilkS")
		)
		(fp_line
			(start -0.7874 0.4064)
			(end -0.7874 -0.4064)
			(stroke
				(width 0.1524)
				(type default)
			)
			(layer "F.SilkS")
		)
		(fp_line
			(start -0.7874 -0.4064)
			(end 0.7874 -0.4064)
			(stroke
				(width 0.1524)
				(type default)
			)
			(layer "F.SilkS")
		)
		(fp_line
			(start 0.67945 0.3048)
			(end 0.120396 0.3048)
			(stroke
				(width 0.1)
				(type default)
			)
			(layer "F.Fab")
		)
		(fp_line
			(start 0.67945 -0.3048)
			(end 0.67945 0.3048)
			(stroke
				(width 0.1)
				(type default)
			)
			(layer "F.Fab")
		)
		(fp_line
			(start 0.12065 -0.2794)
			(end 0.12065 -0.3048)
			(stroke
				(width 0.1)
				(type default)
			)
			(layer "F.Fab")
		)
		(fp_line
			(start 0.12065 -0.3048)
			(end 0.67945 -0.3048)
			(stroke
				(width 0.1)
				(type default)
			)
			(layer "F.Fab")
		)
		(fp_line
			(start 0.120396 0.3048)
			(end 0.120396 0.2794)
			(stroke
				(width 0.1)
				(type default)
			)
			(layer "F.Fab")
		)
		(fp_line
			(start 0.120396 0.2794)
			(end -0.12065 0.2794)
			(stroke
				(width 0.1)
				(type default)
			)
			(layer "F.Fab")
		)
		(fp_line
			(start -0.12065 0.3048)
			(end -0.67945 0.3048)
			(stroke
				(width 0.1)
				(type default)
			)
			(layer "F.Fab")
		)
		(fp_line
			(start -0.12065 0.2794)
			(end -0.12065 0.3048)
			(stroke
				(width 0.1)
				(type default)
			)
			(layer "F.Fab")
		)
		(fp_line
			(start -0.12065 -0.2794)
			(end 0.12065 -0.2794)
			(stroke
				(width 0.1)
				(type default)
			)
			(layer "F.Fab")
		)
		(fp_line
			(start -0.12065 -0.305054)
			(end -0.12065 -0.2794)
			(stroke
				(width 0.1)
				(type default)
			)
			(layer "F.Fab")
		)
		(fp_line
			(start -0.67945 0.3048)
			(end -0.67945 -0.305054)
			(stroke
				(width 0.1)
				(type default)
			)
			(layer "F.Fab")
		)
		(fp_line
			(start -0.67945 -0.305054)
			(end -0.12065 -0.305054)
			(stroke
				(width 0.1)
				(type default)
			)
			(layer "F.Fab")
		)
		(pad "1" smd circle
			(at -0.40005 0 180)
			(size 0 0)
			(layers "F.Cu" "F.Mask" "F.Paste")
			(net "SMB_USB_CPU0_HUB1_SDA_R")
		)
		(pad "2" smd circle
			(at 0.40005 0 180)
			(size 0 0)
			(layers "F.Cu" "F.Mask" "F.Paste")
			(net "SMB_USB_CPU0_HUB1_SDA")
		)
	)
)
